(kicad_pcb
	(version 20260206)
	(generator "pcbnew")
	(generator_version "10.0")
	(general
		(thickness 1.6)
		(legacy_teardrops no)
	)
	(paper "A4")
	(title_block
		(title "01162023_DA0F0TEBIF0_F0T_Expander_BD_F_brd_V02_OCP.brd")
		(comment 1 "Grand Teton / footprints 5106-5111 of 9728")
	)
	(layers
		(0 "F.Cu" signal "TOP")
		(4 "In1.Cu" signal "GND")
		(6 "In2.Cu" signal "VCC")
		(8 "In3.Cu" signal "VCC1")
		(10 "In4.Cu" signal "GND1")
		(12 "In5.Cu" signal "IN1")
		(14 "In6.Cu" signal "GND2")
		(16 "In7.Cu" signal "IN2")
		(18 "In8.Cu" signal "GND3")
		(20 "In9.Cu" signal "IN3")
		(22 "In10.Cu" signal "GND4")
		(24 "In11.Cu" signal "IN4")
		(26 "In12.Cu" signal "GND5")
		(28 "In13.Cu" signal "IN5")
		(30 "In14.Cu" signal "GND6")
		(32 "In15.Cu" signal "IN6")
		(34 "In16.Cu" signal "GND7")
		(2 "B.Cu" signal "BOTTOM")
		(9 "F.Adhes" user "F.Adhesive")
		(11 "B.Adhes" user "B.Adhesive")
		(13 "F.Paste" user "Package Geometry/Pastemask Top")
		(15 "B.Paste" user "Package Geometry/Pastemask Bottom")
		(5 "F.SilkS" user "Ref Des/Silkscreen Top")
		(7 "B.SilkS" user "Ref Des/Silkscreen Bottom")
		(1 "F.Mask" user "Board Geometry/Soldermask Top")
		(3 "B.Mask" user "Board Geometry/Soldermask Bottom")
		(17 "Dwgs.User" user "User.Drawings")
		(19 "Cmts.User" user "User.Comments")
		(21 "Eco1.User" user "User.Eco1")
		(23 "Eco2.User" user "User.Eco2")
		(25 "Edge.Cuts" user "Board Geometry/Outline")
		(27 "Margin" user)
		(31 "F.CrtYd" user "Package Geometry/Place Bound Top")
		(29 "B.CrtYd" user "Package Geometry/Place Bound Bottom")
		(35 "F.Fab" user "Ref Des/Assembly Top")
		(33 "B.Fab" user "Ref Des/Assembly Bottom")
	)
	(footprint ""
		(layer "F.Cu")
		(at 123.100592 -293.5351 90)
		(property "Reference" "PL9"
			(at -4.260596 15.498318 90)
			(unlocked yes)
			(layer "F.SilkS")
			(effects
				(font
					(size 0.7874 0.5842)
					(thickness 0.1524)
				)
				(justify left)
			)
		)
		(property "Value" ""
			(at 0 0 90)
			(layer "F.Fab")
			(effects
				(font
					(size 1.27 1.27)
				)
			)
		)
		(duplicate_pad_numbers_are_jumpers no)
		(fp_line
			(start 4.800092 -3.199892)
			(end 4.800092 -1.6764)
			(stroke
				(width 0.1524)
				(type default)
			)
			(layer "F.SilkS")
		)
		(fp_line
			(start -4.800092 -3.199892)
			(end 4.800092 -3.199892)
			(stroke
				(width 0.1524)
				(type default)
			)
			(layer "F.SilkS")
		)
		(fp_line
			(start -4.800092 -1.6764)
			(end -4.800092 -3.199892)
			(stroke
				(width 0.1524)
				(type default)
			)
			(layer "F.SilkS")
		)
		(fp_line
			(start 4.800092 1.6764)
			(end 4.800092 3.199892)
			(stroke
				(width 0.1524)
				(type default)
			)
			(layer "F.SilkS")
		)
		(fp_line
			(start 4.800092 3.199892)
			(end -4.800092 3.199892)
			(stroke
				(width 0.1524)
				(type default)
			)
			(layer "F.SilkS")
		)
		(fp_line
			(start -4.800092 3.199892)
			(end -4.800092 1.6764)
			(stroke
				(width 0.1524)
				(type default)
			)
			(layer "F.SilkS")
		)
		(fp_line
			(start 4.800092 -3.199892)
			(end 4.800092 3.199892)
			(stroke
				(width 0.1)
				(type default)
			)
			(layer "F.Fab")
		)
		(fp_line
			(start -4.800092 -3.199892)
			(end 4.800092 -3.199892)
			(stroke
				(width 0.1)
				(type default)
			)
			(layer "F.Fab")
		)
		(fp_line
			(start 4.800092 3.199892)
			(end -4.800092 3.199892)
			(stroke
				(width 0.1)
				(type default)
			)
			(layer "F.Fab")
		)
		(fp_line
			(start -4.800092 3.199892)
			(end -4.800092 -3.199892)
			(stroke
				(width 0.1)
				(type default)
			)
			(layer "F.Fab")
		)
		(pad "1" smd rect
			(at -3.074924 0 180)
			(size 3.0988 3.3528)
			(layers "F.Cu" "F.Mask" "F.Paste")
			(net "SW_P0V8_PEX1_PH1")
		)
		(pad "2" smd rect
			(at 3.074924 0 180)
			(size 3.0988 3.3528)
			(layers "F.Cu" "F.Mask" "F.Paste")
			(net "P0V8_PEX1")
		)
	)
	(footprint ""
		(layer "F.Cu")
		(at 459.6638 -230.7844 90)
		(property "Reference" "R6607"
			(at 0 0 90)
			(layer "F.SilkS")
			(hide yes)
			(effects
				(font
					(size 1.27 1.27)
				)
			)
		)
		(property "Value" ""
			(at 0 0 90)
			(layer "F.Fab")
			(effects
				(font
					(size 1.27 1.27)
				)
			)
		)
		(duplicate_pad_numbers_are_jumpers no)
		(fp_line
			(start 0.7874 -0.4064)
			(end 0.7874 0.4064)
			(stroke
				(width 0.1524)
				(type default)
			)
			(layer "F.SilkS")
		)
		(fp_line
			(start -0.7874 -0.4064)
			(end 0.7874 -0.4064)
			(stroke
				(width 0.1524)
				(type default)
			)
			(layer "F.SilkS")
		)
		(fp_line
			(start 0.7874 0.4064)
			(end -0.7874 0.4064)
			(stroke
				(width 0.1524)
				(type default)
			)
			(layer "F.SilkS")
		)
		(fp_line
			(start -0.7874 0.4064)
			(end -0.7874 -0.4064)
			(stroke
				(width 0.1524)
				(type default)
			)
			(layer "F.SilkS")
		)
		(fp_line
			(start -0.12065 -0.305054)
			(end -0.12065 -0.2794)
			(stroke
				(width 0.1)
				(type default)
			)
			(layer "F.Fab")
		)
		(fp_line
			(start -0.67945 -0.305054)
			(end -0.12065 -0.305054)
			(stroke
				(width 0.1)
				(type default)
			)
			(layer "F.Fab")
		)
		(fp_line
			(start 0.67945 -0.3048)
			(end 0.67945 0.3048)
			(stroke
				(width 0.1)
				(type default)
			)
			(layer "F.Fab")
		)
		(fp_line
			(start 0.12065 -0.3048)
			(end 0.67945 -0.3048)
			(stroke
				(width 0.1)
				(type default)
			)
			(layer "F.Fab")
		)
		(fp_line
			(start 0.12065 -0.2794)
			(end 0.12065 -0.3048)
			(stroke
				(width 0.1)
				(type default)
			)
			(layer "F.Fab")
		)
		(fp_line
			(start -0.12065 -0.2794)
			(end 0.12065 -0.2794)
			(stroke
				(width 0.1)
				(type default)
			)
			(layer "F.Fab")
		)
		(fp_line
			(start 0.120396 0.2794)
			(end -0.12065 0.2794)
			(stroke
				(width 0.1)
				(type default)
			)
			(layer "F.Fab")
		)
		(fp_line
			(start -0.12065 0.2794)
			(end -0.12065 0.3048)
			(stroke
				(width 0.1)
				(type default)
			)
			(layer "F.Fab")
		)
		(fp_line
			(start 0.67945 0.3048)
			(end 0.120396 0.3048)
			(stroke
				(width 0.1)
				(type default)
			)
			(layer "F.Fab")
		)
		(fp_line
			(start 0.120396 0.3048)
			(end 0.120396 0.2794)
			(stroke
				(width 0.1)
				(type default)
			)
			(layer "F.Fab")
		)
		(fp_line
			(start -0.12065 0.3048)
			(end -0.67945 0.3048)
			(stroke
				(width 0.1)
				(type default)
			)
			(layer "F.Fab")
		)
		(fp_line
			(start -0.67945 0.3048)
			(end -0.67945 -0.305054)
			(stroke
				(width 0.1)
				(type default)
			)
			(layer "F.Fab")
		)
		(pad "1" smd circle
			(at -0.40005 0 90)
			(size 0 0)
			(layers "F.Cu" "F.Mask" "F.Paste")
			(net "UART_PEX1_SDB_BUF_R_TX")
		)
		(pad "2" smd circle
			(at 0.40005 0 90)
			(size 0 0)
			(layers "F.Cu" "F.Mask" "F.Paste")
			(net "UART_PEX1_SDB_CP2108_TX")
		)
	)
	(footprint ""
		(layer "F.Cu")
		(at 366.938814 -22.867366 90)
		(property "Reference" "C3957"
			(at 0 0 90)
			(layer "F.SilkS")
			(hide yes)
			(effects
				(font
					(size 1.27 1.27)
				)
			)
		)
		(property "Value" ""
			(at 0 0 90)
			(layer "F.Fab")
			(effects
				(font
					(size 1.27 1.27)
				)
			)
		)
		(duplicate_pad_numbers_are_jumpers no)
		(fp_line
			(start 0.7874 -0.4064)
			(end 0.7874 0.4064)
			(stroke
				(width 0.1524)
				(type default)
			)
			(layer "F.SilkS")
		)
		(fp_line
			(start -0.7874 -0.4064)
			(end 0.7874 -0.4064)
			(stroke
				(width 0.1524)
				(type default)
			)
			(layer "F.SilkS")
		)
		(fp_line
			(start 0.7874 0.4064)
			(end -0.7874 0.4064)
			(stroke
				(width 0.1524)
				(type default)
			)
			(layer "F.SilkS")
		)
		(fp_line
			(start -0.7874 0.4064)
			(end -0.7874 -0.4064)
			(stroke
				(width 0.1524)
				(type default)
			)
			(layer "F.SilkS")
		)
		(fp_line
			(start -0.12065 -0.305054)
			(end -0.12065 -0.2794)
			(stroke
				(width 0.1)
				(type default)
			)
			(layer "F.Fab")
		)
		(fp_line
			(start -0.67945 -0.305054)
			(end -0.12065 -0.305054)
			(stroke
				(width 0.1)
				(type default)
			)
			(layer "F.Fab")
		)
		(fp_line
			(start 0.67945 -0.3048)
			(end 0.67945 0.3048)
			(stroke
				(width 0.1)
				(type default)
			)
			(layer "F.Fab")
		)
		(fp_line
			(start 0.12065 -0.3048)
			(end 0.67945 -0.3048)
			(stroke
				(width 0.1)
				(type default)
			)
			(layer "F.Fab")
		)
		(fp_line
			(start 0.12065 -0.2794)
			(end 0.12065 -0.3048)
			(stroke
				(width 0.1)
				(type default)
			)
			(layer "F.Fab")
		)
		(fp_line
			(start -0.12065 -0.2794)
			(end 0.12065 -0.2794)
			(stroke
				(width 0.1)
				(type default)
			)
			(layer "F.Fab")
		)
		(fp_line
			(start 0.120396 0.2794)
			(end -0.12065 0.2794)
			(stroke
				(width 0.1)
				(type default)
			)
			(layer "F.Fab")
		)
		(fp_line
			(start -0.12065 0.2794)
			(end -0.12065 0.3048)
			(stroke
				(width 0.1)
				(type default)
			)
			(layer "F.Fab")
		)
		(fp_line
			(start 0.67945 0.3048)
			(end 0.120396 0.3048)
			(stroke
				(width 0.1)
				(type default)
			)
			(layer "F.Fab")
		)
		(fp_line
			(start 0.120396 0.3048)
			(end 0.120396 0.2794)
			(stroke
				(width 0.1)
				(type default)
			)
			(layer "F.Fab")
		)
		(fp_line
			(start -0.12065 0.3048)
			(end -0.67945 0.3048)
			(stroke
				(width 0.1)
				(type default)
			)
			(layer "F.Fab")
		)
		(fp_line
			(start -0.67945 0.3048)
			(end -0.67945 -0.305054)
			(stroke
				(width 0.1)
				(type default)
			)
			(layer "F.Fab")
		)
		(pad "1" smd circle
			(at -0.40005 0 90)
			(size 0 0)
			(layers "F.Cu" "F.Mask" "F.Paste")
			(net "P12V_SSD12")
		)
		(pad "2" smd circle
			(at 0.40005 0 90)
			(size 0 0)
			(layers "F.Cu" "F.Mask" "F.Paste")
			(net "GND")
		)
	)
	(footprint ""
		(layer "F.Cu")
		(at 136.374124 -72.766682 90)
		(property "Reference" "PR7063"
			(at 0 0 90)
			(layer "F.SilkS")
			(hide yes)
			(effects
				(font
					(size 1.27 1.27)
				)
			)
		)
		(property "Value" ""
			(at 0 0 90)
			(layer "F.Fab")
			(effects
				(font
					(size 1.27 1.27)
				)
			)
		)
		(duplicate_pad_numbers_are_jumpers no)
		(fp_line
			(start 0.7874 -0.4064)
			(end 0.7874 0.4064)
			(stroke
				(width 0.1524)
				(type default)
			)
			(layer "F.SilkS")
		)
		(fp_line
			(start -0.7874 -0.4064)
			(end 0.7874 -0.4064)
			(stroke
				(width 0.1524)
				(type default)
			)
			(layer "F.SilkS")
		)
		(fp_line
			(start 0.7874 0.4064)
			(end -0.7874 0.4064)
			(stroke
				(width 0.1524)
				(type default)
			)
			(layer "F.SilkS")
		)
		(fp_line
			(start -0.7874 0.4064)
			(end -0.7874 -0.4064)
			(stroke
				(width 0.1524)
				(type default)
			)
			(layer "F.SilkS")
		)
		(fp_line
			(start -0.12065 -0.305054)
			(end -0.12065 -0.2794)
			(stroke
				(width 0.1)
				(type default)
			)
			(layer "F.Fab")
		)
		(fp_line
			(start -0.67945 -0.305054)
			(end -0.12065 -0.305054)
			(stroke
				(width 0.1)
				(type default)
			)
			(layer "F.Fab")
		)
		(fp_line
			(start 0.67945 -0.3048)
			(end 0.67945 0.3048)
			(stroke
				(width 0.1)
				(type default)
			)
			(layer "F.Fab")
		)
		(fp_line
			(start 0.12065 -0.3048)
			(end 0.67945 -0.3048)
			(stroke
				(width 0.1)
				(type default)
			)
			(layer "F.Fab")
		)
		(fp_line
			(start 0.12065 -0.2794)
			(end 0.12065 -0.3048)
			(stroke
				(width 0.1)
				(type default)
			)
			(layer "F.Fab")
		)
		(fp_line
			(start -0.12065 -0.2794)
			(end 0.12065 -0.2794)
			(stroke
				(width 0.1)
				(type default)
			)
			(layer "F.Fab")
		)
		(fp_line
			(start 0.120396 0.2794)
			(end -0.12065 0.2794)
			(stroke
				(width 0.1)
				(type default)
			)
			(layer "F.Fab")
		)
		(fp_line
			(start -0.12065 0.2794)
			(end -0.12065 0.3048)
			(stroke
				(width 0.1)
				(type default)
			)
			(layer "F.Fab")
		)
		(fp_line
			(start 0.67945 0.3048)
			(end 0.120396 0.3048)
			(stroke
				(width 0.1)
				(type default)
			)
			(layer "F.Fab")
		)
		(fp_line
			(start 0.120396 0.3048)
			(end 0.120396 0.2794)
			(stroke
				(width 0.1)
				(type default)
			)
			(layer "F.Fab")
		)
		(fp_line
			(start -0.12065 0.3048)
			(end -0.67945 0.3048)
			(stroke
				(width 0.1)
				(type default)
			)
			(layer "F.Fab")
		)
		(fp_line
			(start -0.67945 0.3048)
			(end -0.67945 -0.305054)
			(stroke
				(width 0.1)
				(type default)
			)
			(layer "F.Fab")
		)
		(pad "1" smd circle
			(at -0.40005 0 90)
			(size 0 0)
			(layers "F.Cu" "F.Mask" "F.Paste")
			(net "P12V_SSD4_CO_MODE")
		)
		(pad "2" smd circle
			(at 0.40005 0 90)
			(size 0 0)
			(layers "F.Cu" "F.Mask" "F.Paste")
			(net "GND")
		)
	)
	(footprint ""
		(layer "F.Cu")
		(at 224.84334 -257.975862 -90)
		(property "Reference" "R6494"
			(at 0 0 270)
			(layer "F.SilkS")
			(hide yes)
			(effects
				(font
					(size 1.27 1.27)
				)
			)
		)
		(property "Value" ""
			(at 0 0 270)
			(layer "F.Fab")
			(effects
				(font
					(size 1.27 1.27)
				)
			)
		)
		(duplicate_pad_numbers_are_jumpers no)
		(fp_line
			(start -0.7874 0.4064)
			(end -0.7874 -0.4064)
			(stroke
				(width 0.1524)
				(type default)
			)
			(layer "F.SilkS")
		)
		(fp_line
			(start 0.7874 0.4064)
			(end -0.7874 0.4064)
			(stroke
				(width 0.1524)
				(type default)
			)
			(layer "F.SilkS")
		)
		(fp_line
			(start -0.7874 -0.4064)
			(end 0.7874 -0.4064)
			(stroke
				(width 0.1524)
				(type default)
			)
			(layer "F.SilkS")
		)
		(fp_line
			(start 0.7874 -0.4064)
			(end 0.7874 0.4064)
			(stroke
				(width 0.1524)
				(type default)
			)
			(layer "F.SilkS")
		)
		(fp_line
			(start -0.67945 0.3048)
			(end -0.67945 -0.305054)
			(stroke
				(width 0.1)
				(type default)
			)
			(layer "F.Fab")
		)
		(fp_line
			(start -0.12065 0.3048)
			(end -0.67945 0.3048)
			(stroke
				(width 0.1)
				(type default)
			)
			(layer "F.Fab")
		)
		(fp_line
			(start 0.120396 0.3048)
			(end 0.120396 0.2794)
			(stroke
				(width 0.1)
				(type default)
			)
			(layer "F.Fab")
		)
		(fp_line
			(start 0.67945 0.3048)
			(end 0.120396 0.3048)
			(stroke
				(width 0.1)
				(type default)
			)
			(layer "F.Fab")
		)
		(fp_line
			(start -0.12065 0.2794)
			(end -0.12065 0.3048)
			(stroke
				(width 0.1)
				(type default)
			)
			(layer "F.Fab")
		)
		(fp_line
			(start 0.120396 0.2794)
			(end -0.12065 0.2794)
			(stroke
				(width 0.1)
				(type default)
			)
			(layer "F.Fab")
		)
		(fp_line
			(start -0.12065 -0.2794)
			(end 0.12065 -0.2794)
			(stroke
				(width 0.1)
				(type default)
			)
			(layer "F.Fab")
		)
		(fp_line
			(start 0.12065 -0.2794)
			(end 0.12065 -0.3048)
			(stroke
				(width 0.1)
				(type default)
			)
			(layer "F.Fab")
		)
		(fp_line
			(start 0.12065 -0.3048)
			(end 0.67945 -0.3048)
			(stroke
				(width 0.1)
				(type default)
			)
			(layer "F.Fab")
		)
		(fp_line
			(start 0.67945 -0.3048)
			(end 0.67945 0.3048)
			(stroke
				(width 0.1)
				(type default)
			)
			(layer "F.Fab")
		)
		(fp_line
			(start -0.67945 -0.305054)
			(end -0.12065 -0.305054)
			(stroke
				(width 0.1)
				(type default)
			)
			(layer "F.Fab")
		)
		(fp_line
			(start -0.12065 -0.305054)
			(end -0.12065 -0.2794)
			(stroke
				(width 0.1)
				(type default)
			)
			(layer "F.Fab")
		)
		(pad "1" smd circle
			(at -0.40005 0 270)
			(size 0 0)
			(layers "F.Cu" "F.Mask" "F.Paste")
			(net "P1V25_SERDES_VDDPLL_PEX1")
		)
		(pad "2" smd circle
			(at 0.40005 0 270)
			(size 0 0)
			(layers "F.Cu" "F.Mask" "F.Paste")
			(net "P1V25_SERDES_VDDPLL_PEX1_C3")
		)
	)
	(footprint ""
		(layer "F.Cu")
		(at 298.57319 -210.094068 -90)
		(property "Reference" "R3366"
			(at 0 0 270)
			(layer "F.SilkS")
			(hide yes)
			(effects
				(font
					(size 1.27 1.27)
				)
			)
		)
		(property "Value" ""
			(at 0 0 270)
			(layer "F.Fab")
			(effects
				(font
					(size 1.27 1.27)
				)
			)
		)
		(duplicate_pad_numbers_are_jumpers no)
		(fp_line
			(start -0.7874 0.4064)
			(end -0.7874 -0.4064)
			(stroke
				(width 0.1524)
				(type default)
			)
			(layer "F.SilkS")
		)
		(fp_line
			(start 0.7874 0.4064)
			(end -0.7874 0.4064)
			(stroke
				(width 0.1524)
				(type default)
			)
			(layer "F.SilkS")
		)
		(fp_line
			(start -0.7874 -0.4064)
			(end 0.7874 -0.4064)
			(stroke
				(width 0.1524)
				(type default)
			)
			(layer "F.SilkS")
		)
		(fp_line
			(start 0.7874 -0.4064)
			(end 0.7874 0.4064)
			(stroke
				(width 0.1524)
				(type default)
			)
			(layer "F.SilkS")
		)
		(fp_line
			(start -0.67945 0.3048)
			(end -0.67945 -0.305054)
			(stroke
				(width 0.1)
				(type default)
			)
			(layer "F.Fab")
		)
		(fp_line
			(start -0.12065 0.3048)
			(end -0.67945 0.3048)
			(stroke
				(width 0.1)
				(type default)
			)
			(layer "F.Fab")
		)
		(fp_line
			(start 0.120396 0.3048)
			(end 0.120396 0.2794)
			(stroke
				(width 0.1)
				(type default)
			)
			(layer "F.Fab")
		)
		(fp_line
			(start 0.67945 0.3048)
			(end 0.120396 0.3048)
			(stroke
				(width 0.1)
				(type default)
			)
			(layer "F.Fab")
		)
		(fp_line
			(start -0.12065 0.2794)
			(end -0.12065 0.3048)
			(stroke
				(width 0.1)
				(type default)
			)
			(layer "F.Fab")
		)
		(fp_line
			(start 0.120396 0.2794)
			(end -0.12065 0.2794)
			(stroke
				(width 0.1)
				(type default)
			)
			(layer "F.Fab")
		)
		(fp_line
			(start -0.12065 -0.2794)
			(end 0.12065 -0.2794)
			(stroke
				(width 0.1)
				(type default)
			)
			(layer "F.Fab")
		)
		(fp_line
			(start 0.12065 -0.2794)
			(end 0.12065 -0.3048)
			(stroke
				(width 0.1)
				(type default)
			)
			(layer "F.Fab")
		)
		(fp_line
			(start 0.12065 -0.3048)
			(end 0.67945 -0.3048)
			(stroke
				(width 0.1)
				(type default)
			)
			(layer "F.Fab")
		)
		(fp_line
			(start 0.67945 -0.3048)
			(end 0.67945 0.3048)
			(stroke
				(width 0.1)
				(type default)
			)
			(layer "F.Fab")
		)
		(fp_line
			(start -0.67945 -0.305054)
			(end -0.12065 -0.305054)
			(stroke
				(width 0.1)
				(type default)
			)
			(layer "F.Fab")
		)
		(fp_line
			(start -0.12065 -0.305054)
			(end -0.12065 -0.2794)
			(stroke
				(width 0.1)
				(type default)
			)
			(layer "F.Fab")
		)
		(pad "1" smd circle
			(at -0.40005 0 270)
			(size 0 0)
			(layers "F.Cu" "F.Mask" "F.Paste")
			(net "SPI_BIC1_CLK_LS23_R")
		)
		(pad "2" smd circle
			(at 0.40005 0 270)
			(size 0 0)
			(layers "F.Cu" "F.Mask" "F.Paste")
			(net "SPI_BIC1_CLK_LS23")
		)
	)
)
